# Bryce Canyon_Front_Drive_Plane_Board_Stackup.xlsx — PCB Test Plan_HVM(90+) (pcb-stackup)
|  | Board vendor give feedback of quantity in yellow columns based on the AQL table or description. |  |  |  |  |  |  |  |  |  |  |  |  |  |  |
|  | Wiwynn PM give feedback in blue columns |  |  |  |  |  |  |  |  |  |  |  |  |  |  |
| Person to be informed : PCB vendor, EE, SI, PM, PSM, Buyer, SQM |  |  |  |  |  |  |  |  |  |  |  |  |  |  |  |
| Simple flow : SI (test requirements) -> PM/AM (Total PCBS demand) -> Buyer -> Board Vendor (yellow column feedback) -> Buyer -> Person to be informed (Check and Track) |  |  |  |  |  |  |  |  |  |  |  |  |  |  |  |
| PO(purchase order) : If there are many POs for this PCB, 1st sample quantity is based on 1st PO, 2nd sample quantity is based on 2nd PO. |  |  |  |  |  |  |  |  |  |  |  |  |  |  |  |
| Project Name | PCB name | PCB# (1XXXX-XX) | Product Stage | Batch# | PCB Vendor | Production  Lot size | PCBs Demand | Delta-L Coupon (PCB Vendor) | Delta-L Coupon (3rd Party Lab) | Impedance Coupon (PCB Vendor) | In-board trace correlation (PCB Vendor) | X-section Analysis (PCB Vendor) | IST (3rd Party Lab) | IPC-6012D (3rd Party Lab) | Note |
| Bryce Canyon | FDPB | 16315-1 | HVM(90+ days) | N/A |  |  | TBD | Yes | No | Yes | No | No | No | No | Need Test? (Yes, No) |
| Tracking Code On Both Of Coupon And PCB |  |  |  |  |  |  |  | N/A |  | N/A |  |  |  |  |  |
| Test Item Acceptance Criteria |  |  |  |  |  |  |  | c = 0 |  | c = 0 |  |  |  |  |  |
| Test Item Sampling Quantity |  |  |  |  |  |  |  | 5 pcs/production lot/quarter, with max total of 30 pcs |  | Mil-STD 105E single sampling plan, AQL 0.65, level 2 |  |  |  |  |  |
| Test Time(working days) |  |  |  |  |  |  |  |  |  |  |  |  |  |  |  |
| Test Item Shipping Quantity |  |  |  |  |  |  |  |  |  |  |  |  |  |  |  |
| Shipping Address |  |  |  |  |  |  |  |  |  |  |  |  |  |  |  |
| Receiver Name |  |  |  |  |  |  |  |  |  |  |  |  |  |  |  |
| Receiver Phone# |  |  |  |  |  |  |  |  |  |  |  |  |  |  |  |
| Project Name | PCB name | PCB# (1XXXX-XX) | Product Stage | Batch# | PCB Vendor | Production  Lot size | PCBs Demand | Delta-L Coupon (PCB Vendor) | Delta-L Coupon (3rd Party Lab) | Impedance Coupon (PCB Vendor) | In-board trace correlation (PCB Vendor) | X-section Analysis (PCB Vendor) | IST (3rd Party Lab) | IPC-6012D (3rd Party Lab) | Note |
| Bryce Canyon | SCC | 16316-1 | HVM(90+ days) | N/A |  |  | TBD | No | No | Yes | No | No | No | No | Need Test? (Yes, No) |
| Tracking Code On Both Of Coupon And PCB |  |  |  |  |  |  |  |  |  | N/A |  |  |  |  |  |
| Test Item Acceptance Criteria |  |  |  |  |  |  |  |  |  | c = 0 |  |  |  |  |  |
| Test Item Sampling Quantity |  |  |  |  |  |  |  |  |  | Mil-STD 105E single sampling plan, AQL 0.65, level 2 |  |  |  |  |  |
| Test Time (working days) |  |  |  |  |  |  |  |  |  |  |  |  |  |  |  |
| Test Item Shipping Quantity |  |  |  |  |  |  |  |  |  |  |  |  |  |  |  |
| Shipping Address |  |  |  |  |  |  |  |  |  |  |  |  |  |  |  |
| Receiver Name |  |  |  |  |  |  |  |  |  |  |  |  |  |  |  |
| Receiver Phone# |  |  |  |  |  |  |  |  |  |  |  |  |  |  |  |
| Project Name | PCB name | PCB# (1XXXX-XX) | Product Stage | Batch# | PCB Vendor | Production  Lot size | PCBs Demand | Delta-L Coupon (PCB Vendor) | Delta-L Coupon (3rd Party Lab) | Impedance Coupon (PCB Vendor) | In-board trace correlation (PCB Vendor) | X-section Analysis (PCB Vendor) | IST (3rd Party Lab) | IPC-6012D (3rd Party Lab) | Note |
| Bryce Canyon | RDPB | 16317-1 | HVM(90+ days) | N/A |  |  | TBD | Yes | No | Yes | No | No | No | No | Need Test? (Yes, No) |
| Tracking Code On Both Of Coupon And PCB |  |  |  |  |  |  |  | N/A |  | N/A |  |  |  |  |  |
| Test Item Acceptance Criteria |  |  |  |  |  |  |  | c = 0 |  | c = 0 |  |  |  |  |  |
| Test Item Sampling Quantity |  |  |  |  |  |  |  | 5 pcs/production lot/quarter, with max total of 30 pcs |  | Mil-STD 105E single sampling plan, AQL 0.65, level 2 |  |  |  |  |  |
| Test Time (working days) |  |  |  |  |  |  |  |  |  |  |  |  |  |  |  |
| Test Item Shipping Quantity |  |  |  |  |  |  |  |  |  |  |  |  |  |  |  |
| Shipping Address |  |  |  |  |  |  |  |  |  |  |  |  |  |  |  |
| Receiver Name |  |  |  |  |  |  |  |  |  |  |  |  |  |  |  |
| Receiver Phone# |  |  |  |  |  |  |  |  |  |  |  |  |  |  |  |
| Project Name | PCB name | PCB# (1XXXX-XX) | Product Stage | Batch# | PCB Vendor | Production  Lot size | PCBs Demand | Delta-L Coupon (PCB Vendor) | Delta-L Coupon (3rd Party Lab) | Impedance Coupon (PCB Vendor) | In-board trace correlation (PCB Vendor) | X-section Analysis (PCB Vendor) | IST (3rd Party Lab) | IPC-6012D (3rd Party Lab) | Note |
| Bryce Canyon | IOM IOC | 16318-1 | HVM(90+ days) | N/A |  |  | TBD | No | No | Yes | No | No | No | No | Need Test? (Yes, No) |
| Tracking Code On Both Of Coupon And PCB |  |  |  |  |  |  |  |  |  | N/A |  |  |  |  |  |
| Test Item Acceptance Criteria |  |  |  |  |  |  |  |  |  | c = 0 |  |  |  |  |  |
| Test Item Sampling Quantity |  |  |  |  |  |  |  |  |  | Mil-STD 105E single sampling plan, AQL 0.65, level 2 |  |  |  |  |  |
| Test Time (working days) |  |  |  |  |  |  |  |  |  |  |  |  |  |  |  |
| Test Item Shipping Quantity |  |  |  |  |  |  |  |  |  |  |  |  |  |  |  |
| Shipping Address |  |  |  |  |  |  |  |  |  |  |  |  |  |  |  |
| Receiver Name |  |  |  |  |  |  |  |  |  |  |  |  |  |  |  |
| Receiver Phone# |  |  |  |  |  |  |  |  |  |  |  |  |  |  |  |
| Project Name | PCB name | PCB# (1XXXX-XX) | Product Stage | Batch# | PCB Vendor | Production  Lot size | PCBs Demand | Delta-L Coupon (PCB Vendor) | Delta-L Coupon (3rd Party Lab) | Impedance Coupon (PCB Vendor) | In-board trace correlation (PCB Vendor) | X-section Analysis (PCB Vendor) | IST (3rd Party Lab) | IPC-6012D (3rd Party Lab) | Note |
| Bryce Canyon | IOM M2 | 16342-1 | HVM(90+ days) | N/A |  |  | TBD | No | No | Yes | No | No | No | No | Need Test? (Yes, No) |
| Tracking Code On Both Of Coupon And PCB |  |  |  |  |  |  |  |  |  | N/A |  |  |  |  |  |
| Test Item Acceptance Criteria |  |  |  |  |  |  |  |  |  | c = 0 |  |  |  |  |  |
| Test Item Sampling Quantity |  |  |  |  |  |  |  |  |  | Mil-STD 105E single sampling plan, AQL 0.65, level 2 |  |  |  |  |  |
| Test Time (working days) |  |  |  |  |  |  |  |  |  |  |  |  |  |  |  |
| Test Item Shipping Quantity |  |  |  |  |  |  |  |  |  |  |  |  |  |  |  |
| Shipping Address |  |  |  |  |  |  |  |  |  |  |  |  |  |  |  |
| Receiver Name |  |  |  |  |  |  |  |  |  |  |  |  |  |  |  |
| Receiver Phone# |  |  |  |  |  |  |  |  |  |  |  |  |  |  |  |
